#ISCELL
  mstr_misc dns *
  *
#ISCELL
  pure_quanta quanta_title_block_c *
  *
#ISCELL
  logical_power universal_gnd *
  page162_i1
#ISCELL
  logical_power universal_gnd *
  page162_i10
#CELL
  pure_quanta q_res *
  page162_i11
#CELL
  pure_quanta q_res *
  page162_i12
#ISCELL
  logical_power universal_power *
  page162_i13
#ISCELL
  standard offpage *
  page162_i14
#ISCELL
  standard offpage *
  page162_i15
#ISCELL
  logical_power universal_gnd *
  page162_i16
#CELL
  pure_quanta q_res *
  page162_i17
#CELL
  pure_quanta q_res *
  page162_i18
#ISCELL
  standard offpage *
  page162_i19
#CELL
  pure_quanta q_res *
  page162_i2
#ISCELL
  standard offpage *
  page162_i20
#ISCELL
  logical_power universal_gnd *
  page162_i21
#ISCELL
  logical_power universal_gnd *
  page162_i22
#CELL
  pure_quanta q_res *
  page162_i23
#CELL
  pure_quanta q_res *
  page162_i24
#CELL
  pure_quanta q_cap_diffbus *
  page162_i25
#CELL
  pure_quanta q_cap_diffbus *
  page162_i26
#ISCELL
  standard offpage *
  page162_i27
#ISCELL
  standard offpage *
  page162_i28
#ISCELL
  standard offpage *
  page162_i29
#CELL
  pure_quanta q_res *
  page162_i3
#ISCELL
  standard offpage *
  page162_i30
#ISCELL
  standard offpage *
  page162_i31
#ISCELL
  standard offpage *
  page162_i32
#ISCELL
  standard offpage *
  page162_i33
#ISCELL
  standard offpage *
  page162_i34
#CELL
  pure_quanta q_inductor *
  page162_i35
#ISCELL
  logical_power universal_gnd *
  page162_i36
#CELL
  pure_quanta q_cap *
  page162_i37
#ISCELL
  logical_power universal_power *
  page162_i38
#ISCELL
  logical_power universal_gnd *
  page162_i39
#ISCELL
  logical_power universal_power *
  page162_i4
#CELL
  pure_quanta q_res *
  page162_i40
#CELL
  pure_quanta q_res *
  page162_i41
#ISCELL
  logical_power universal_power *
  page162_i42
#CELL
  pure_quanta pi3eqx1002ezrex *
  page162_i43
#CELL
  pure_quanta q_cap *
  page162_i44
#CELL
  pure_quanta q_cap *
  page162_i45
#ISCELL
  logical_power universal_gnd *
  page162_i46
#ISCELL
  logical_power universal_gnd *
  page162_i47
#CELL
  pure_quanta q_res *
  page162_i48
#CELL
  pure_quanta q_res *
  page162_i49
#ISCELL
  logical_power universal_gnd *
  page162_i5
#ISCELL
  standard offpage *
  page162_i50
#ISCELL
  standard offpage *
  page162_i51
#ISCELL
  standard offpage *
  page162_i52
#ISCELL
  standard offpage *
  page162_i53
#CELL
  pure_quanta q_cap *
  page162_i54
#CELL
  pure_quanta q_cap *
  page162_i55
#CELL
  pure_quanta q_cap *
  page162_i56
#CELL
  pure_quanta q_cap *
  page162_i57
#ISCELL
  standard offpage *
  page162_i58
#ISCELL
  standard offpage *
  page162_i59
#CELL
  pure_quanta q_res *
  page162_i6
#ISCELL
  standard offpage *
  page162_i60
#ISCELL
  standard offpage *
  page162_i61
#ISCELL
  logical_power universal_gnd *
  page162_i62
#CELL
  pure_quanta q_res *
  page162_i63
#ISCELL
  standard offpage *
  page162_i64
#CELL
  pure_quanta q_res *
  page162_i65
#ISCELL
  logical_power universal_power *
  page162_i66
#ISCELL
  logical_power universal_gnd *
  page162_i67
#CELL
  pure_quanta q_res *
  page162_i68
#CELL
  pure_quanta q_res *
  page162_i69
#CELL
  pure_quanta q_res *
  page162_i7
#ISCELL
  logical_power universal_power *
  page162_i70
#ISCELL
  standard offpage *
  page162_i71
#ISCELL
  standard offpage *
  page162_i8
#ISCELL
  standard offpage *
  page162_i9
